(kicad_pcb
	(version 20260206)
	(generator "pcbnew")
	(generator_version "10.0")
	(general
		(thickness 1.6)
		(legacy_teardrops no)
	)
	(paper "A4")
	(title_block
		(title "01162023_DA0F0TEBIF0_F0T_Expander_BD_F_brd_V02_OCP.brd")
		(comment 1 "Grand Teton / footprints 5295-5301 of 9728")
	)
	(layers
		(0 "F.Cu" signal "TOP")
		(4 "In1.Cu" signal "GND")
		(6 "In2.Cu" signal "VCC")
		(8 "In3.Cu" signal "VCC1")
		(10 "In4.Cu" signal "GND1")
		(12 "In5.Cu" signal "IN1")
		(14 "In6.Cu" signal "GND2")
		(16 "In7.Cu" signal "IN2")
		(18 "In8.Cu" signal "GND3")
		(20 "In9.Cu" signal "IN3")
		(22 "In10.Cu" signal "GND4")
		(24 "In11.Cu" signal "IN4")
		(26 "In12.Cu" signal "GND5")
		(28 "In13.Cu" signal "IN5")
		(30 "In14.Cu" signal "GND6")
		(32 "In15.Cu" signal "IN6")
		(34 "In16.Cu" signal "GND7")
		(2 "B.Cu" signal "BOTTOM")
		(9 "F.Adhes" user "F.Adhesive")
		(11 "B.Adhes" user "B.Adhesive")
		(13 "F.Paste" user "Package Geometry/Pastemask Top")
		(15 "B.Paste" user "Package Geometry/Pastemask Bottom")
		(5 "F.SilkS" user "Ref Des/Silkscreen Top")
		(7 "B.SilkS" user "Ref Des/Silkscreen Bottom")
		(1 "F.Mask" user "Board Geometry/Soldermask Top")
		(3 "B.Mask" user "Board Geometry/Soldermask Bottom")
		(17 "Dwgs.User" user "User.Drawings")
		(19 "Cmts.User" user "User.Comments")
		(21 "Eco1.User" user "User.Eco1")
		(23 "Eco2.User" user "User.Eco2")
		(25 "Edge.Cuts" user "Board Geometry/Outline")
		(27 "Margin" user)
		(31 "F.CrtYd" user "Package Geometry/Place Bound Top")
		(29 "B.CrtYd" user "Package Geometry/Place Bound Bottom")
		(35 "F.Fab" user "Ref Des/Assembly Top")
		(33 "B.Fab" user "Ref Des/Assembly Bottom")
	)
	(footprint ""
		(layer "F.Cu")
		(at 171.979844 -139.6492)
		(property "Reference" "R109"
			(at 0 0 0)
			(layer "F.SilkS")
			(hide yes)
			(effects
				(font
					(size 1.27 1.27)
				)
			)
		)
		(property "Value" ""
			(at 0 0 0)
			(layer "F.Fab")
			(effects
				(font
					(size 1.27 1.27)
				)
			)
		)
		(duplicate_pad_numbers_are_jumpers no)
		(fp_line
			(start -0.7874 -0.4064)
			(end 0.7874 -0.4064)
			(stroke
				(width 0.1524)
				(type default)
			)
			(layer "F.SilkS")
		)
		(fp_line
			(start -0.7874 0.4064)
			(end -0.7874 -0.4064)
			(stroke
				(width 0.1524)
				(type default)
			)
			(layer "F.SilkS")
		)
		(fp_line
			(start 0.7874 -0.4064)
			(end 0.7874 0.4064)
			(stroke
				(width 0.1524)
				(type default)
			)
			(layer "F.SilkS")
		)
		(fp_line
			(start 0.7874 0.4064)
			(end -0.7874 0.4064)
			(stroke
				(width 0.1524)
				(type default)
			)
			(layer "F.SilkS")
		)
		(fp_line
			(start -0.67945 -0.305054)
			(end -0.12065 -0.305054)
			(stroke
				(width 0.1)
				(type default)
			)
			(layer "F.Fab")
		)
		(fp_line
			(start -0.67945 0.3048)
			(end -0.67945 -0.305054)
			(stroke
				(width 0.1)
				(type default)
			)
			(layer "F.Fab")
		)
		(fp_line
			(start -0.12065 -0.305054)
			(end -0.12065 -0.2794)
			(stroke
				(width 0.1)
				(type default)
			)
			(layer "F.Fab")
		)
		(fp_line
			(start -0.12065 -0.2794)
			(end 0.12065 -0.2794)
			(stroke
				(width 0.1)
				(type default)
			)
			(layer "F.Fab")
		)
		(fp_line
			(start -0.12065 0.2794)
			(end -0.12065 0.3048)
			(stroke
				(width 0.1)
				(type default)
			)
			(layer "F.Fab")
		)
		(fp_line
			(start -0.12065 0.3048)
			(end -0.67945 0.3048)
			(stroke
				(width 0.1)
				(type default)
			)
			(layer "F.Fab")
		)
		(fp_line
			(start 0.120396 0.2794)
			(end -0.12065 0.2794)
			(stroke
				(width 0.1)
				(type default)
			)
			(layer "F.Fab")
		)
		(fp_line
			(start 0.120396 0.3048)
			(end 0.120396 0.2794)
			(stroke
				(width 0.1)
				(type default)
			)
			(layer "F.Fab")
		)
		(fp_line
			(start 0.12065 -0.3048)
			(end 0.67945 -0.3048)
			(stroke
				(width 0.1)
				(type default)
			)
			(layer "F.Fab")
		)
		(fp_line
			(start 0.12065 -0.2794)
			(end 0.12065 -0.3048)
			(stroke
				(width 0.1)
				(type default)
			)
			(layer "F.Fab")
		)
		(fp_line
			(start 0.67945 -0.3048)
			(end 0.67945 0.3048)
			(stroke
				(width 0.1)
				(type default)
			)
			(layer "F.Fab")
		)
		(fp_line
			(start 0.67945 0.3048)
			(end 0.120396 0.3048)
			(stroke
				(width 0.1)
				(type default)
			)
			(layer "F.Fab")
		)
		(pad "1" smd circle
			(at -0.40005 0)
			(size 0 0)
			(layers "F.Cu" "F.Mask" "F.Paste")
			(net "PRSNTB2_NIC2_N")
		)
		(pad "2" smd circle
			(at 0.40005 0)
			(size 0 0)
			(layers "F.Cu" "F.Mask" "F.Paste")
			(net "P3V3_AUX")
		)
	)
	(footprint ""
		(layer "F.Cu")
		(at 334.130396 -120.79224)
		(property "Reference" "R6039"
			(at 0 0 0)
			(layer "F.SilkS")
			(hide yes)
			(effects
				(font
					(size 1.27 1.27)
				)
			)
		)
		(property "Value" ""
			(at 0 0 0)
			(layer "F.Fab")
			(effects
				(font
					(size 1.27 1.27)
				)
			)
		)
		(duplicate_pad_numbers_are_jumpers no)
		(fp_line
			(start -0.7874 -0.4064)
			(end 0.7874 -0.4064)
			(stroke
				(width 0.1524)
				(type default)
			)
			(layer "F.SilkS")
		)
		(fp_line
			(start -0.7874 0.4064)
			(end -0.7874 -0.4064)
			(stroke
				(width 0.1524)
				(type default)
			)
			(layer "F.SilkS")
		)
		(fp_line
			(start 0.7874 -0.4064)
			(end 0.7874 0.4064)
			(stroke
				(width 0.1524)
				(type default)
			)
			(layer "F.SilkS")
		)
		(fp_line
			(start 0.7874 0.4064)
			(end -0.7874 0.4064)
			(stroke
				(width 0.1524)
				(type default)
			)
			(layer "F.SilkS")
		)
		(fp_line
			(start -0.67945 -0.305054)
			(end -0.12065 -0.305054)
			(stroke
				(width 0.1)
				(type default)
			)
			(layer "F.Fab")
		)
		(fp_line
			(start -0.67945 0.3048)
			(end -0.67945 -0.305054)
			(stroke
				(width 0.1)
				(type default)
			)
			(layer "F.Fab")
		)
		(fp_line
			(start -0.12065 -0.305054)
			(end -0.12065 -0.2794)
			(stroke
				(width 0.1)
				(type default)
			)
			(layer "F.Fab")
		)
		(fp_line
			(start -0.12065 -0.2794)
			(end 0.12065 -0.2794)
			(stroke
				(width 0.1)
				(type default)
			)
			(layer "F.Fab")
		)
		(fp_line
			(start -0.12065 0.2794)
			(end -0.12065 0.3048)
			(stroke
				(width 0.1)
				(type default)
			)
			(layer "F.Fab")
		)
		(fp_line
			(start -0.12065 0.3048)
			(end -0.67945 0.3048)
			(stroke
				(width 0.1)
				(type default)
			)
			(layer "F.Fab")
		)
		(fp_line
			(start 0.120396 0.2794)
			(end -0.12065 0.2794)
			(stroke
				(width 0.1)
				(type default)
			)
			(layer "F.Fab")
		)
		(fp_line
			(start 0.120396 0.3048)
			(end 0.120396 0.2794)
			(stroke
				(width 0.1)
				(type default)
			)
			(layer "F.Fab")
		)
		(fp_line
			(start 0.12065 -0.3048)
			(end 0.67945 -0.3048)
			(stroke
				(width 0.1)
				(type default)
			)
			(layer "F.Fab")
		)
		(fp_line
			(start 0.12065 -0.2794)
			(end 0.12065 -0.3048)
			(stroke
				(width 0.1)
				(type default)
			)
			(layer "F.Fab")
		)
		(fp_line
			(start 0.67945 -0.3048)
			(end 0.67945 0.3048)
			(stroke
				(width 0.1)
				(type default)
			)
			(layer "F.Fab")
		)
		(fp_line
			(start 0.67945 0.3048)
			(end 0.120396 0.3048)
			(stroke
				(width 0.1)
				(type default)
			)
			(layer "F.Fab")
		)
		(pad "1" smd circle
			(at -0.40005 0)
			(size 0 0)
			(layers "F.Cu" "F.Mask" "F.Paste")
			(net "P3V3_NIC5")
		)
		(pad "2" smd circle
			(at 0.40005 0)
			(size 0 0)
			(layers "F.Cu" "F.Mask" "F.Paste")
			(net "P3V3_NIC5_PG_G1")
		)
	)
	(footprint ""
		(layer "F.Cu")
		(at 8.211058 -61.386974)
		(property "Reference" "R4482"
			(at 0 0 0)
			(layer "F.SilkS")
			(hide yes)
			(effects
				(font
					(size 1.27 1.27)
				)
			)
		)
		(property "Value" ""
			(at 0 0 0)
			(layer "F.Fab")
			(effects
				(font
					(size 1.27 1.27)
				)
			)
		)
		(duplicate_pad_numbers_are_jumpers no)
		(fp_line
			(start -0.7874 -0.4064)
			(end 0.7874 -0.4064)
			(stroke
				(width 0.1524)
				(type default)
			)
			(layer "F.SilkS")
		)
		(fp_line
			(start -0.7874 0.4064)
			(end -0.7874 -0.4064)
			(stroke
				(width 0.1524)
				(type default)
			)
			(layer "F.SilkS")
		)
		(fp_line
			(start 0.7874 -0.4064)
			(end 0.7874 0.4064)
			(stroke
				(width 0.1524)
				(type default)
			)
			(layer "F.SilkS")
		)
		(fp_line
			(start 0.7874 0.4064)
			(end -0.7874 0.4064)
			(stroke
				(width 0.1524)
				(type default)
			)
			(layer "F.SilkS")
		)
		(fp_line
			(start -0.67945 -0.305054)
			(end -0.12065 -0.305054)
			(stroke
				(width 0.1)
				(type default)
			)
			(layer "F.Fab")
		)
		(fp_line
			(start -0.67945 0.3048)
			(end -0.67945 -0.305054)
			(stroke
				(width 0.1)
				(type default)
			)
			(layer "F.Fab")
		)
		(fp_line
			(start -0.12065 -0.305054)
			(end -0.12065 -0.2794)
			(stroke
				(width 0.1)
				(type default)
			)
			(layer "F.Fab")
		)
		(fp_line
			(start -0.12065 -0.2794)
			(end 0.12065 -0.2794)
			(stroke
				(width 0.1)
				(type default)
			)
			(layer "F.Fab")
		)
		(fp_line
			(start -0.12065 0.2794)
			(end -0.12065 0.3048)
			(stroke
				(width 0.1)
				(type default)
			)
			(layer "F.Fab")
		)
		(fp_line
			(start -0.12065 0.3048)
			(end -0.67945 0.3048)
			(stroke
				(width 0.1)
				(type default)
			)
			(layer "F.Fab")
		)
		(fp_line
			(start 0.120396 0.2794)
			(end -0.12065 0.2794)
			(stroke
				(width 0.1)
				(type default)
			)
			(layer "F.Fab")
		)
		(fp_line
			(start 0.120396 0.3048)
			(end 0.120396 0.2794)
			(stroke
				(width 0.1)
				(type default)
			)
			(layer "F.Fab")
		)
		(fp_line
			(start 0.12065 -0.3048)
			(end 0.67945 -0.3048)
			(stroke
				(width 0.1)
				(type default)
			)
			(layer "F.Fab")
		)
		(fp_line
			(start 0.12065 -0.2794)
			(end 0.12065 -0.3048)
			(stroke
				(width 0.1)
				(type default)
			)
			(layer "F.Fab")
		)
		(fp_line
			(start 0.67945 -0.3048)
			(end 0.67945 0.3048)
			(stroke
				(width 0.1)
				(type default)
			)
			(layer "F.Fab")
		)
		(fp_line
			(start 0.67945 0.3048)
			(end 0.120396 0.3048)
			(stroke
				(width 0.1)
				(type default)
			)
			(layer "F.Fab")
		)
		(pad "1" smd circle
			(at -0.40005 0)
			(size 0 0)
			(layers "F.Cu" "F.Mask" "F.Paste")
			(net "PWRGD_P3V3_SSD0")
		)
		(pad "2" smd circle
			(at 0.40005 0)
			(size 0 0)
			(layers "F.Cu" "F.Mask" "F.Paste")
			(net "PWRGD_P3V3_SSD0_R")
		)
	)
	(footprint ""
		(layer "F.Cu")
		(at 169.759884 -193.836798)
		(property "Reference" "R3290"
			(at 0 0 0)
			(layer "F.SilkS")
			(hide yes)
			(effects
				(font
					(size 1.27 1.27)
				)
			)
		)
		(property "Value" ""
			(at 0 0 0)
			(layer "F.Fab")
			(effects
				(font
					(size 1.27 1.27)
				)
			)
		)
		(duplicate_pad_numbers_are_jumpers no)
		(fp_line
			(start -0.7874 -0.4064)
			(end 0.7874 -0.4064)
			(stroke
				(width 0.1524)
				(type default)
			)
			(layer "F.SilkS")
		)
		(fp_line
			(start -0.7874 0.4064)
			(end -0.7874 -0.4064)
			(stroke
				(width 0.1524)
				(type default)
			)
			(layer "F.SilkS")
		)
		(fp_line
			(start 0.7874 -0.4064)
			(end 0.7874 0.4064)
			(stroke
				(width 0.1524)
				(type default)
			)
			(layer "F.SilkS")
		)
		(fp_line
			(start 0.7874 0.4064)
			(end -0.7874 0.4064)
			(stroke
				(width 0.1524)
				(type default)
			)
			(layer "F.SilkS")
		)
		(fp_line
			(start -0.67945 -0.305054)
			(end -0.12065 -0.305054)
			(stroke
				(width 0.1)
				(type default)
			)
			(layer "F.Fab")
		)
		(fp_line
			(start -0.67945 0.3048)
			(end -0.67945 -0.305054)
			(stroke
				(width 0.1)
				(type default)
			)
			(layer "F.Fab")
		)
		(fp_line
			(start -0.12065 -0.305054)
			(end -0.12065 -0.2794)
			(stroke
				(width 0.1)
				(type default)
			)
			(layer "F.Fab")
		)
		(fp_line
			(start -0.12065 -0.2794)
			(end 0.12065 -0.2794)
			(stroke
				(width 0.1)
				(type default)
			)
			(layer "F.Fab")
		)
		(fp_line
			(start -0.12065 0.2794)
			(end -0.12065 0.3048)
			(stroke
				(width 0.1)
				(type default)
			)
			(layer "F.Fab")
		)
		(fp_line
			(start -0.12065 0.3048)
			(end -0.67945 0.3048)
			(stroke
				(width 0.1)
				(type default)
			)
			(layer "F.Fab")
		)
		(fp_line
			(start 0.120396 0.2794)
			(end -0.12065 0.2794)
			(stroke
				(width 0.1)
				(type default)
			)
			(layer "F.Fab")
		)
		(fp_line
			(start 0.120396 0.3048)
			(end 0.120396 0.2794)
			(stroke
				(width 0.1)
				(type default)
			)
			(layer "F.Fab")
		)
		(fp_line
			(start 0.12065 -0.3048)
			(end 0.67945 -0.3048)
			(stroke
				(width 0.1)
				(type default)
			)
			(layer "F.Fab")
		)
		(fp_line
			(start 0.12065 -0.2794)
			(end 0.12065 -0.3048)
			(stroke
				(width 0.1)
				(type default)
			)
			(layer "F.Fab")
		)
		(fp_line
			(start 0.67945 -0.3048)
			(end 0.67945 0.3048)
			(stroke
				(width 0.1)
				(type default)
			)
			(layer "F.Fab")
		)
		(fp_line
			(start 0.67945 0.3048)
			(end 0.120396 0.3048)
			(stroke
				(width 0.1)
				(type default)
			)
			(layer "F.Fab")
		)
		(pad "1" smd circle
			(at -0.40005 0)
			(size 0 0)
			(layers "F.Cu" "F.Mask" "F.Paste")
			(net "SPI_BIC1_MISO_LS01_R")
		)
		(pad "2" smd circle
			(at 0.40005 0)
			(size 0 0)
			(layers "F.Cu" "F.Mask" "F.Paste")
			(net "SPI_BIC1_MISO_LS01")
		)
	)
	(footprint ""
		(layer "F.Cu")
		(at 449.956428 -20.467574 180)
		(property "Reference" "R1734"
			(at 0 0 180)
			(layer "F.SilkS")
			(hide yes)
			(effects
				(font
					(size 1.27 1.27)
				)
			)
		)
		(property "Value" ""
			(at 0 0 180)
			(layer "F.Fab")
			(effects
				(font
					(size 1.27 1.27)
				)
			)
		)
		(duplicate_pad_numbers_are_jumpers no)
		(fp_line
			(start 0.7874 0.4064)
			(end -0.7874 0.4064)
			(stroke
				(width 0.1524)
				(type default)
			)
			(layer "F.SilkS")
		)
		(fp_line
			(start 0.7874 -0.4064)
			(end 0.7874 0.4064)
			(stroke
				(width 0.1524)
				(type default)
			)
			(layer "F.SilkS")
		)
		(fp_line
			(start -0.7874 0.4064)
			(end -0.7874 -0.4064)
			(stroke
				(width 0.1524)
				(type default)
			)
			(layer "F.SilkS")
		)
		(fp_line
			(start -0.7874 -0.4064)
			(end 0.7874 -0.4064)
			(stroke
				(width 0.1524)
				(type default)
			)
			(layer "F.SilkS")
		)
		(fp_line
			(start 0.67945 0.3048)
			(end 0.120396 0.3048)
			(stroke
				(width 0.1)
				(type default)
			)
			(layer "F.Fab")
		)
		(fp_line
			(start 0.67945 -0.3048)
			(end 0.67945 0.3048)
			(stroke
				(width 0.1)
				(type default)
			)
			(layer "F.Fab")
		)
		(fp_line
			(start 0.12065 -0.2794)
			(end 0.12065 -0.3048)
			(stroke
				(width 0.1)
				(type default)
			)
			(layer "F.Fab")
		)
		(fp_line
			(start 0.12065 -0.3048)
			(end 0.67945 -0.3048)
			(stroke
				(width 0.1)
				(type default)
			)
			(layer "F.Fab")
		)
		(fp_line
			(start 0.120396 0.3048)
			(end 0.120396 0.2794)
			(stroke
				(width 0.1)
				(type default)
			)
			(layer "F.Fab")
		)
		(fp_line
			(start 0.120396 0.2794)
			(end -0.12065 0.2794)
			(stroke
				(width 0.1)
				(type default)
			)
			(layer "F.Fab")
		)
		(fp_line
			(start -0.12065 0.3048)
			(end -0.67945 0.3048)
			(stroke
				(width 0.1)
				(type default)
			)
			(layer "F.Fab")
		)
		(fp_line
			(start -0.12065 0.2794)
			(end -0.12065 0.3048)
			(stroke
				(width 0.1)
				(type default)
			)
			(layer "F.Fab")
		)
		(fp_line
			(start -0.12065 -0.2794)
			(end 0.12065 -0.2794)
			(stroke
				(width 0.1)
				(type default)
			)
			(layer "F.Fab")
		)
		(fp_line
			(start -0.12065 -0.305054)
			(end -0.12065 -0.2794)
			(stroke
				(width 0.1)
				(type default)
			)
			(layer "F.Fab")
		)
		(fp_line
			(start -0.67945 0.3048)
			(end -0.67945 -0.305054)
			(stroke
				(width 0.1)
				(type default)
			)
			(layer "F.Fab")
		)
		(fp_line
			(start -0.67945 -0.305054)
			(end -0.12065 -0.305054)
			(stroke
				(width 0.1)
				(type default)
			)
			(layer "F.Fab")
		)
		(pad "1" smd circle
			(at -0.40005 0 180)
			(size 0 0)
			(layers "F.Cu" "F.Mask" "F.Paste")
			(net "P3V3_SSD15")
		)
		(pad "2" smd circle
			(at 0.40005 0 180)
			(size 0 0)
			(layers "F.Cu" "F.Mask" "F.Paste")
			(net "SMB_ISO_SSD15_SDA")
		)
	)
	(footprint ""
		(layer "F.Cu")
		(at 120.473978 -27.006296 -90)
		(property "Reference" "PC924"
			(at 0 0 270)
			(layer "F.SilkS")
			(hide yes)
			(effects
				(font
					(size 1.27 1.27)
				)
			)
		)
		(property "Value" ""
			(at 0 0 270)
			(layer "F.Fab")
			(effects
				(font
					(size 1.27 1.27)
				)
			)
		)
		(duplicate_pad_numbers_are_jumpers no)
		(fp_line
			(start -0.7874 0.4064)
			(end -0.7874 -0.4064)
			(stroke
				(width 0.1524)
				(type default)
			)
			(layer "F.SilkS")
		)
		(fp_line
			(start 0.7874 0.4064)
			(end -0.7874 0.4064)
			(stroke
				(width 0.1524)
				(type default)
			)
			(layer "F.SilkS")
		)
		(fp_line
			(start -0.7874 -0.4064)
			(end 0.7874 -0.4064)
			(stroke
				(width 0.1524)
				(type default)
			)
			(layer "F.SilkS")
		)
		(fp_line
			(start 0.7874 -0.4064)
			(end 0.7874 0.4064)
			(stroke
				(width 0.1524)
				(type default)
			)
			(layer "F.SilkS")
		)
		(fp_line
			(start -0.67945 0.3048)
			(end -0.67945 -0.305054)
			(stroke
				(width 0.1)
				(type default)
			)
			(layer "F.Fab")
		)
		(fp_line
			(start -0.12065 0.3048)
			(end -0.67945 0.3048)
			(stroke
				(width 0.1)
				(type default)
			)
			(layer "F.Fab")
		)
		(fp_line
			(start 0.120396 0.3048)
			(end 0.120396 0.2794)
			(stroke
				(width 0.1)
				(type default)
			)
			(layer "F.Fab")
		)
		(fp_line
			(start 0.67945 0.3048)
			(end 0.120396 0.3048)
			(stroke
				(width 0.1)
				(type default)
			)
			(layer "F.Fab")
		)
		(fp_line
			(start -0.12065 0.2794)
			(end -0.12065 0.3048)
			(stroke
				(width 0.1)
				(type default)
			)
			(layer "F.Fab")
		)
		(fp_line
			(start 0.120396 0.2794)
			(end -0.12065 0.2794)
			(stroke
				(width 0.1)
				(type default)
			)
			(layer "F.Fab")
		)
		(fp_line
			(start -0.12065 -0.2794)
			(end 0.12065 -0.2794)
			(stroke
				(width 0.1)
				(type default)
			)
			(layer "F.Fab")
		)
		(fp_line
			(start 0.12065 -0.2794)
			(end 0.12065 -0.3048)
			(stroke
				(width 0.1)
				(type default)
			)
			(layer "F.Fab")
		)
		(fp_line
			(start 0.12065 -0.3048)
			(end 0.67945 -0.3048)
			(stroke
				(width 0.1)
				(type default)
			)
			(layer "F.Fab")
		)
		(fp_line
			(start 0.67945 -0.3048)
			(end 0.67945 0.3048)
			(stroke
				(width 0.1)
				(type default)
			)
			(layer "F.Fab")
		)
		(fp_line
			(start -0.67945 -0.305054)
			(end -0.12065 -0.305054)
			(stroke
				(width 0.1)
				(type default)
			)
			(layer "F.Fab")
		)
		(fp_line
			(start -0.12065 -0.305054)
			(end -0.12065 -0.2794)
			(stroke
				(width 0.1)
				(type default)
			)
			(layer "F.Fab")
		)
		(pad "1" smd circle
			(at -0.40005 0 270)
			(size 0 0)
			(layers "F.Cu" "F.Mask" "F.Paste")
			(net "P3V3_SSD4_CO_MODE")
		)
		(pad "2" smd circle
			(at 0.40005 0 270)
			(size 0 0)
			(layers "F.Cu" "F.Mask" "F.Paste")
			(net "GND")
		)
	)
	(footprint ""
		(layer "F.Cu")
		(at 133.599428 -356.244906 90)
		(property "Reference" "C2267"
			(at 0 0 90)
			(layer "F.SilkS")
			(hide yes)
			(effects
				(font
					(size 1.27 1.27)
				)
			)
		)
		(property "Value" ""
			(at 0 0 90)
			(layer "F.Fab")
			(effects
				(font
					(size 1.27 1.27)
				)
			)
		)
		(duplicate_pad_numbers_are_jumpers no)
		(fp_line
			(start 0.299974 -0.150114)
			(end 0.299974 0.150114)
			(stroke
				(width 0.1)
				(type default)
			)
			(layer "F.Fab")
		)
		(fp_line
			(start -0.299974 -0.150114)
			(end 0.299974 -0.150114)
			(stroke
				(width 0.1)
				(type default)
			)
			(layer "F.Fab")
		)
		(fp_line
			(start 0.299974 0.150114)
			(end -0.299974 0.150114)
			(stroke
				(width 0.1)
				(type default)
			)
			(layer "F.Fab")
		)
		(fp_line
			(start -0.299974 0.150114)
			(end -0.299974 -0.150114)
			(stroke
				(width 0.1)
				(type default)
			)
			(layer "F.Fab")
		)
		(pad "1" smd rect
			(at -0.2667 0 90)
			(size 0.3048 0.381)
			(layers "F.Cu" "F.Mask" "F.Paste")
			(net "P5E_PEX1_STN5_TX_DP<83>")
		)
		(pad "2" smd rect
			(at 0.2667 0 90)
			(size 0.3048 0.381)
			(layers "F.Cu" "F.Mask" "F.Paste")
			(net "P5E_PEX1_STN5_TX_C_DP<83>")
		)
	)
)
